(kicad_pcb
	(version 20260206)
	(generator "pcbnew")
	(generator_version "10.0")
	(general
		(thickness 1.6)
		(legacy_teardrops no)
	)
	(paper "A4")
	(title_block
		(title "01162023_DA0F0TEBIF0_F0T_Expander_BD_F_brd_V02_OCP.brd")
		(comment 1 "Grand Teton / footprints 2792-2798 of 9728")
	)
	(layers
		(0 "F.Cu" signal "TOP")
		(4 "In1.Cu" signal "GND")
		(6 "In2.Cu" signal "VCC")
		(8 "In3.Cu" signal "VCC1")
		(10 "In4.Cu" signal "GND1")
		(12 "In5.Cu" signal "IN1")
		(14 "In6.Cu" signal "GND2")
		(16 "In7.Cu" signal "IN2")
		(18 "In8.Cu" signal "GND3")
		(20 "In9.Cu" signal "IN3")
		(22 "In10.Cu" signal "GND4")
		(24 "In11.Cu" signal "IN4")
		(26 "In12.Cu" signal "GND5")
		(28 "In13.Cu" signal "IN5")
		(30 "In14.Cu" signal "GND6")
		(32 "In15.Cu" signal "IN6")
		(34 "In16.Cu" signal "GND7")
		(2 "B.Cu" signal "BOTTOM")
		(9 "F.Adhes" user "F.Adhesive")
		(11 "B.Adhes" user "B.Adhesive")
		(13 "F.Paste" user "Package Geometry/Pastemask Top")
		(15 "B.Paste" user "Package Geometry/Pastemask Bottom")
		(5 "F.SilkS" user "Ref Des/Silkscreen Top")
		(7 "B.SilkS" user "Ref Des/Silkscreen Bottom")
		(1 "F.Mask" user "Board Geometry/Soldermask Top")
		(3 "B.Mask" user "Board Geometry/Soldermask Bottom")
		(17 "Dwgs.User" user "User.Drawings")
		(19 "Cmts.User" user "User.Comments")
		(21 "Eco1.User" user "User.Eco1")
		(23 "Eco2.User" user "User.Eco2")
		(25 "Edge.Cuts" user "Board Geometry/Outline")
		(27 "Margin" user)
		(31 "F.CrtYd" user "Package Geometry/Place Bound Top")
		(29 "B.CrtYd" user "Package Geometry/Place Bound Bottom")
		(35 "F.Fab" user "Ref Des/Assembly Top")
		(33 "B.Fab" user "Ref Des/Assembly Bottom")
	)
	(footprint ""
		(layer "F.Cu")
		(at 447.323718 -106.413808 180)
		(property "Reference" "PD19"
			(at 4.425442 2.137156 0)
			(unlocked yes)
			(layer "F.SilkS")
			(effects
				(font
					(size 0.7874 0.5842)
					(thickness 0.1524)
				)
				(justify left)
			)
		)
		(property "Value" ""
			(at 0 0 180)
			(layer "F.Fab")
			(effects
				(font
					(size 1.27 1.27)
				)
			)
		)
		(duplicate_pad_numbers_are_jumpers no)
		(fp_line
			(start 4.107942 1.459992)
			(end -3.400044 1.459992)
			(stroke
				(width 0.1524)
				(type default)
			)
			(layer "F.SilkS")
		)
		(fp_line
			(start 4.107942 -1.459992)
			(end 4.107942 1.459992)
			(stroke
				(width 0.1524)
				(type default)
			)
			(layer "F.SilkS")
		)
		(fp_line
			(start -3.400044 1.459992)
			(end -3.400044 -1.459992)
			(stroke
				(width 0.1524)
				(type default)
			)
			(layer "F.SilkS")
		)
		(fp_line
			(start -3.400044 -1.459992)
			(end 4.107942 -1.459992)
			(stroke
				(width 0.1524)
				(type default)
			)
			(layer "F.SilkS")
		)
		(fp_rect
			(start 4.107942 -1.459992)
			(end 3.308096 1.459992)
			(stroke
				(width 0)
				(type default)
			)
			(fill yes)
			(layer "F.SilkS")
		)
		(fp_line
			(start 2.29997 1.459992)
			(end -2.29997 1.459992)
			(stroke
				(width 0.1)
				(type default)
			)
			(layer "F.Fab")
		)
		(fp_line
			(start 2.29997 -1.459992)
			(end 2.29997 1.459992)
			(stroke
				(width 0.1)
				(type default)
			)
			(layer "F.Fab")
		)
		(fp_line
			(start -2.29997 1.459992)
			(end -2.29997 -1.459992)
			(stroke
				(width 0.1)
				(type default)
			)
			(layer "F.Fab")
		)
		(fp_line
			(start -2.29997 -1.459992)
			(end 2.29997 -1.459992)
			(stroke
				(width 0.1)
				(type default)
			)
			(layer "F.Fab")
		)
		(fp_text user "-"
			(at 3.91033 -1.53035 0)
			(unlocked yes)
			(layer "F.SilkS")
			(effects
				(font
					(size 1.905 1.4224)
					(thickness 0.1524)
				)
				(justify left)
			)
		)
		(fp_text user "+"
			(at -3.27533 -2.242058 180)
			(unlocked yes)
			(layer "F.SilkS")
			(effects
				(font
					(size 1.905 1.4224)
					(thickness 0.1524)
				)
				(justify left)
			)
		)
		(fp_text user "-"
			(at 5.4102 0.29845 0)
			(unlocked yes)
			(layer "F.Fab")
			(effects
				(font
					(size 1.905 1.4224)
					(thickness 0.1524)
				)
				(justify left)
			)
		)
		(fp_text user "+"
			(at -4.7752 -0.12065 180)
			(unlocked yes)
			(layer "F.Fab")
			(effects
				(font
					(size 1.905 1.4224)
					(thickness 0.1524)
				)
				(justify left)
			)
		)
		(pad "A" smd rect
			(at -1.999996 0 270)
			(size 1.7018 2.5146)
			(layers "F.Cu" "F.Mask" "F.Paste")
			(net "GND")
		)
		(pad "C" smd rect
			(at 1.999996 0 270)
			(size 1.7018 2.5146)
			(layers "F.Cu" "F.Mask" "F.Paste")
			(net "P12V_NIC7_R")
		)
	)
	(footprint ""
		(layer "F.Cu")
		(at 360.213656 -393.247118)
		(property "Reference" "R6700"
			(at 0 0 0)
			(layer "F.SilkS")
			(hide yes)
			(effects
				(font
					(size 1.27 1.27)
				)
			)
		)
		(property "Value" ""
			(at 0 0 0)
			(layer "F.Fab")
			(effects
				(font
					(size 1.27 1.27)
				)
			)
		)
		(duplicate_pad_numbers_are_jumpers no)
		(fp_line
			(start -0.7874 -0.4064)
			(end 0.7874 -0.4064)
			(stroke
				(width 0.1524)
				(type default)
			)
			(layer "F.SilkS")
		)
		(fp_line
			(start -0.7874 0.4064)
			(end -0.7874 -0.4064)
			(stroke
				(width 0.1524)
				(type default)
			)
			(layer "F.SilkS")
		)
		(fp_line
			(start 0.7874 -0.4064)
			(end 0.7874 0.4064)
			(stroke
				(width 0.1524)
				(type default)
			)
			(layer "F.SilkS")
		)
		(fp_line
			(start 0.7874 0.4064)
			(end -0.7874 0.4064)
			(stroke
				(width 0.1524)
				(type default)
			)
			(layer "F.SilkS")
		)
		(fp_line
			(start -0.67945 -0.305054)
			(end -0.12065 -0.305054)
			(stroke
				(width 0.1)
				(type default)
			)
			(layer "F.Fab")
		)
		(fp_line
			(start -0.67945 0.3048)
			(end -0.67945 -0.305054)
			(stroke
				(width 0.1)
				(type default)
			)
			(layer "F.Fab")
		)
		(fp_line
			(start -0.12065 -0.305054)
			(end -0.12065 -0.2794)
			(stroke
				(width 0.1)
				(type default)
			)
			(layer "F.Fab")
		)
		(fp_line
			(start -0.12065 -0.2794)
			(end 0.12065 -0.2794)
			(stroke
				(width 0.1)
				(type default)
			)
			(layer "F.Fab")
		)
		(fp_line
			(start -0.12065 0.2794)
			(end -0.12065 0.3048)
			(stroke
				(width 0.1)
				(type default)
			)
			(layer "F.Fab")
		)
		(fp_line
			(start -0.12065 0.3048)
			(end -0.67945 0.3048)
			(stroke
				(width 0.1)
				(type default)
			)
			(layer "F.Fab")
		)
		(fp_line
			(start 0.120396 0.2794)
			(end -0.12065 0.2794)
			(stroke
				(width 0.1)
				(type default)
			)
			(layer "F.Fab")
		)
		(fp_line
			(start 0.120396 0.3048)
			(end 0.120396 0.2794)
			(stroke
				(width 0.1)
				(type default)
			)
			(layer "F.Fab")
		)
		(fp_line
			(start 0.12065 -0.3048)
			(end 0.67945 -0.3048)
			(stroke
				(width 0.1)
				(type default)
			)
			(layer "F.Fab")
		)
		(fp_line
			(start 0.12065 -0.2794)
			(end 0.12065 -0.3048)
			(stroke
				(width 0.1)
				(type default)
			)
			(layer "F.Fab")
		)
		(fp_line
			(start 0.67945 -0.3048)
			(end 0.67945 0.3048)
			(stroke
				(width 0.1)
				(type default)
			)
			(layer "F.Fab")
		)
		(fp_line
			(start 0.67945 0.3048)
			(end 0.120396 0.3048)
			(stroke
				(width 0.1)
				(type default)
			)
			(layer "F.Fab")
		)
		(pad "1" smd circle
			(at -0.40005 0)
			(size 0 0)
			(layers "F.Cu" "F.Mask" "F.Paste")
			(net "MB_3V3IO_RSVD1_ISO")
		)
		(pad "2" smd circle
			(at 0.40005 0)
			(size 0 0)
			(layers "F.Cu" "F.Mask" "F.Paste")
			(net "MB_3V3IO_RSVD1")
		)
	)
	(footprint ""
		(layer "F.Cu")
		(at 268.402816 -93.542104)
		(property "Reference" "R1054"
			(at 0 0 0)
			(layer "F.SilkS")
			(hide yes)
			(effects
				(font
					(size 1.27 1.27)
				)
			)
		)
		(property "Value" ""
			(at 0 0 0)
			(layer "F.Fab")
			(effects
				(font
					(size 1.27 1.27)
				)
			)
		)
		(duplicate_pad_numbers_are_jumpers no)
		(fp_line
			(start -0.7874 -0.4064)
			(end 0.7874 -0.4064)
			(stroke
				(width 0.1524)
				(type default)
			)
			(layer "F.SilkS")
		)
		(fp_line
			(start -0.7874 0.4064)
			(end -0.7874 -0.4064)
			(stroke
				(width 0.1524)
				(type default)
			)
			(layer "F.SilkS")
		)
		(fp_line
			(start 0.7874 -0.4064)
			(end 0.7874 0.4064)
			(stroke
				(width 0.1524)
				(type default)
			)
			(layer "F.SilkS")
		)
		(fp_line
			(start 0.7874 0.4064)
			(end -0.7874 0.4064)
			(stroke
				(width 0.1524)
				(type default)
			)
			(layer "F.SilkS")
		)
		(fp_line
			(start -0.67945 -0.305054)
			(end -0.12065 -0.305054)
			(stroke
				(width 0.1)
				(type default)
			)
			(layer "F.Fab")
		)
		(fp_line
			(start -0.67945 0.3048)
			(end -0.67945 -0.305054)
			(stroke
				(width 0.1)
				(type default)
			)
			(layer "F.Fab")
		)
		(fp_line
			(start -0.12065 -0.305054)
			(end -0.12065 -0.2794)
			(stroke
				(width 0.1)
				(type default)
			)
			(layer "F.Fab")
		)
		(fp_line
			(start -0.12065 -0.2794)
			(end 0.12065 -0.2794)
			(stroke
				(width 0.1)
				(type default)
			)
			(layer "F.Fab")
		)
		(fp_line
			(start -0.12065 0.2794)
			(end -0.12065 0.3048)
			(stroke
				(width 0.1)
				(type default)
			)
			(layer "F.Fab")
		)
		(fp_line
			(start -0.12065 0.3048)
			(end -0.67945 0.3048)
			(stroke
				(width 0.1)
				(type default)
			)
			(layer "F.Fab")
		)
		(fp_line
			(start 0.120396 0.2794)
			(end -0.12065 0.2794)
			(stroke
				(width 0.1)
				(type default)
			)
			(layer "F.Fab")
		)
		(fp_line
			(start 0.120396 0.3048)
			(end 0.120396 0.2794)
			(stroke
				(width 0.1)
				(type default)
			)
			(layer "F.Fab")
		)
		(fp_line
			(start 0.12065 -0.3048)
			(end 0.67945 -0.3048)
			(stroke
				(width 0.1)
				(type default)
			)
			(layer "F.Fab")
		)
		(fp_line
			(start 0.12065 -0.2794)
			(end 0.12065 -0.3048)
			(stroke
				(width 0.1)
				(type default)
			)
			(layer "F.Fab")
		)
		(fp_line
			(start 0.67945 -0.3048)
			(end 0.67945 0.3048)
			(stroke
				(width 0.1)
				(type default)
			)
			(layer "F.Fab")
		)
		(fp_line
			(start 0.67945 0.3048)
			(end 0.120396 0.3048)
			(stroke
				(width 0.1)
				(type default)
			)
			(layer "F.Fab")
		)
		(pad "1" smd circle
			(at -0.40005 0)
			(size 0 0)
			(layers "F.Cu" "F.Mask" "F.Paste")
			(net "PU_CK440_SHFT_LD_N")
		)
		(pad "2" smd circle
			(at 0.40005 0)
			(size 0 0)
			(layers "F.Cu" "F.Mask" "F.Paste")
			(net "P3V3")
		)
	)
	(footprint ""
		(layer "F.Cu")
		(at 252.350016 -297.369992)
		(property "Reference" "H141"
			(at -1.56845 -4.033774 0)
			(unlocked yes)
			(layer "F.SilkS")
			(effects
				(font
					(size 0.7874 0.5842)
					(thickness 0.1524)
				)
				(justify left)
			)
		)
		(property "Value" ""
			(at 0 0 0)
			(layer "F.Fab")
			(effects
				(font
					(size 1.27 1.27)
				)
			)
		)
		(duplicate_pad_numbers_are_jumpers no)
		(pad "1" thru_hole circle
			(at 0 0)
			(size 6.5024 6.5024)
			(drill 3.2004)
			(layers "*.Cu" "*.Mask")
			(remove_unused_layers no)
			(net "GND")
			(clearance -1.397)
		)
	)
	(footprint ""
		(layer "F.Cu")
		(at 123.71324 -134.042404)
		(property "Reference" "R4452"
			(at 0 0 0)
			(layer "F.SilkS")
			(hide yes)
			(effects
				(font
					(size 1.27 1.27)
				)
			)
		)
		(property "Value" ""
			(at 0 0 0)
			(layer "F.Fab")
			(effects
				(font
					(size 1.27 1.27)
				)
			)
		)
		(duplicate_pad_numbers_are_jumpers no)
		(fp_line
			(start -0.7874 -0.4064)
			(end 0.7874 -0.4064)
			(stroke
				(width 0.1524)
				(type default)
			)
			(layer "F.SilkS")
		)
		(fp_line
			(start -0.7874 0.4064)
			(end -0.7874 -0.4064)
			(stroke
				(width 0.1524)
				(type default)
			)
			(layer "F.SilkS")
		)
		(fp_line
			(start 0.7874 -0.4064)
			(end 0.7874 0.4064)
			(stroke
				(width 0.1524)
				(type default)
			)
			(layer "F.SilkS")
		)
		(fp_line
			(start 0.7874 0.4064)
			(end -0.7874 0.4064)
			(stroke
				(width 0.1524)
				(type default)
			)
			(layer "F.SilkS")
		)
		(fp_line
			(start -0.67945 -0.305054)
			(end -0.12065 -0.305054)
			(stroke
				(width 0.1)
				(type default)
			)
			(layer "F.Fab")
		)
		(fp_line
			(start -0.67945 0.3048)
			(end -0.67945 -0.305054)
			(stroke
				(width 0.1)
				(type default)
			)
			(layer "F.Fab")
		)
		(fp_line
			(start -0.12065 -0.305054)
			(end -0.12065 -0.2794)
			(stroke
				(width 0.1)
				(type default)
			)
			(layer "F.Fab")
		)
		(fp_line
			(start -0.12065 -0.2794)
			(end 0.12065 -0.2794)
			(stroke
				(width 0.1)
				(type default)
			)
			(layer "F.Fab")
		)
		(fp_line
			(start -0.12065 0.2794)
			(end -0.12065 0.3048)
			(stroke
				(width 0.1)
				(type default)
			)
			(layer "F.Fab")
		)
		(fp_line
			(start -0.12065 0.3048)
			(end -0.67945 0.3048)
			(stroke
				(width 0.1)
				(type default)
			)
			(layer "F.Fab")
		)
		(fp_line
			(start 0.120396 0.2794)
			(end -0.12065 0.2794)
			(stroke
				(width 0.1)
				(type default)
			)
			(layer "F.Fab")
		)
		(fp_line
			(start 0.120396 0.3048)
			(end 0.120396 0.2794)
			(stroke
				(width 0.1)
				(type default)
			)
			(layer "F.Fab")
		)
		(fp_line
			(start 0.12065 -0.3048)
			(end 0.67945 -0.3048)
			(stroke
				(width 0.1)
				(type default)
			)
			(layer "F.Fab")
		)
		(fp_line
			(start 0.12065 -0.2794)
			(end 0.12065 -0.3048)
			(stroke
				(width 0.1)
				(type default)
			)
			(layer "F.Fab")
		)
		(fp_line
			(start 0.67945 -0.3048)
			(end 0.67945 0.3048)
			(stroke
				(width 0.1)
				(type default)
			)
			(layer "F.Fab")
		)
		(fp_line
			(start 0.67945 0.3048)
			(end 0.120396 0.3048)
			(stroke
				(width 0.1)
				(type default)
			)
			(layer "F.Fab")
		)
		(pad "1" smd circle
			(at -0.40005 0)
			(size 0 0)
			(layers "F.Cu" "F.Mask" "F.Paste")
			(net "HP_NIC2_EN")
		)
		(pad "2" smd circle
			(at 0.40005 0)
			(size 0 0)
			(layers "F.Cu" "F.Mask" "F.Paste")
			(net "P12V_NIC2_EN_R")
		)
	)
	(footprint ""
		(layer "F.Cu")
		(at 114.802158 -161.106866)
		(property "Reference" "PC39"
			(at 0 0 0)
			(layer "F.SilkS")
			(hide yes)
			(effects
				(font
					(size 1.27 1.27)
				)
			)
		)
		(property "Value" ""
			(at 0 0 0)
			(layer "F.Fab")
			(effects
				(font
					(size 1.27 1.27)
				)
			)
		)
		(duplicate_pad_numbers_are_jumpers no)
		(fp_line
			(start -0.7874 -0.4064)
			(end 0.7874 -0.4064)
			(stroke
				(width 0.1524)
				(type default)
			)
			(layer "F.SilkS")
		)
		(fp_line
			(start -0.7874 0.4064)
			(end -0.7874 -0.4064)
			(stroke
				(width 0.1524)
				(type default)
			)
			(layer "F.SilkS")
		)
		(fp_line
			(start 0.7874 -0.4064)
			(end 0.7874 0.4064)
			(stroke
				(width 0.1524)
				(type default)
			)
			(layer "F.SilkS")
		)
		(fp_line
			(start 0.7874 0.4064)
			(end -0.7874 0.4064)
			(stroke
				(width 0.1524)
				(type default)
			)
			(layer "F.SilkS")
		)
		(fp_line
			(start -0.67945 -0.305054)
			(end -0.12065 -0.305054)
			(stroke
				(width 0.1)
				(type default)
			)
			(layer "F.Fab")
		)
		(fp_line
			(start -0.67945 0.3048)
			(end -0.67945 -0.305054)
			(stroke
				(width 0.1)
				(type default)
			)
			(layer "F.Fab")
		)
		(fp_line
			(start -0.12065 -0.305054)
			(end -0.12065 -0.2794)
			(stroke
				(width 0.1)
				(type default)
			)
			(layer "F.Fab")
		)
		(fp_line
			(start -0.12065 -0.2794)
			(end 0.12065 -0.2794)
			(stroke
				(width 0.1)
				(type default)
			)
			(layer "F.Fab")
		)
		(fp_line
			(start -0.12065 0.2794)
			(end -0.12065 0.3048)
			(stroke
				(width 0.1)
				(type default)
			)
			(layer "F.Fab")
		)
		(fp_line
			(start -0.12065 0.3048)
			(end -0.67945 0.3048)
			(stroke
				(width 0.1)
				(type default)
			)
			(layer "F.Fab")
		)
		(fp_line
			(start 0.120396 0.2794)
			(end -0.12065 0.2794)
			(stroke
				(width 0.1)
				(type default)
			)
			(layer "F.Fab")
		)
		(fp_line
			(start 0.120396 0.3048)
			(end 0.120396 0.2794)
			(stroke
				(width 0.1)
				(type default)
			)
			(layer "F.Fab")
		)
		(fp_line
			(start 0.12065 -0.3048)
			(end 0.67945 -0.3048)
			(stroke
				(width 0.1)
				(type default)
			)
			(layer "F.Fab")
		)
		(fp_line
			(start 0.12065 -0.2794)
			(end 0.12065 -0.3048)
			(stroke
				(width 0.1)
				(type default)
			)
			(layer "F.Fab")
		)
		(fp_line
			(start 0.67945 -0.3048)
			(end 0.67945 0.3048)
			(stroke
				(width 0.1)
				(type default)
			)
			(layer "F.Fab")
		)
		(fp_line
			(start 0.67945 0.3048)
			(end 0.120396 0.3048)
			(stroke
				(width 0.1)
				(type default)
			)
			(layer "F.Fab")
		)
		(pad "1" smd circle
			(at -0.40005 0)
			(size 0 0)
			(layers "F.Cu" "F.Mask" "F.Paste")
			(net "P3V3_AUX_FB")
		)
		(pad "2" smd circle
			(at 0.40005 0)
			(size 0 0)
			(layers "F.Cu" "F.Mask" "F.Paste")
			(net "SH_P3V3_AUX_FB")
		)
	)
	(footprint ""
		(layer "F.Cu")
		(at 23.330408 -343.952322 90)
		(property "Reference" "C190"
			(at 0 0 90)
			(layer "F.SilkS")
			(hide yes)
			(effects
				(font
					(size 1.27 1.27)
				)
			)
		)
		(property "Value" ""
			(at 0 0 90)
			(layer "F.Fab")
			(effects
				(font
					(size 1.27 1.27)
				)
			)
		)
		(duplicate_pad_numbers_are_jumpers no)
		(fp_line
			(start 0.299974 -0.150114)
			(end 0.299974 0.150114)
			(stroke
				(width 0.1)
				(type default)
			)
			(layer "F.Fab")
		)
		(fp_line
			(start -0.299974 -0.150114)
			(end 0.299974 -0.150114)
			(stroke
				(width 0.1)
				(type default)
			)
			(layer "F.Fab")
		)
		(fp_line
			(start 0.299974 0.150114)
			(end -0.299974 0.150114)
			(stroke
				(width 0.1)
				(type default)
			)
			(layer "F.Fab")
		)
		(fp_line
			(start -0.299974 0.150114)
			(end -0.299974 -0.150114)
			(stroke
				(width 0.1)
				(type default)
			)
			(layer "F.Fab")
		)
		(pad "1" smd rect
			(at -0.2667 0 90)
			(size 0.3048 0.381)
			(layers "F.Cu" "F.Mask" "F.Paste")
			(net "P5E_PEX0_STN7_TX_DN<113>")
		)
		(pad "2" smd rect
			(at 0.2667 0 90)
			(size 0.3048 0.381)
			(layers "F.Cu" "F.Mask" "F.Paste")
			(net "P5E_PEX0_STN7_TX_C_DN<113>")
		)
	)
)
